# SCM (Grand Teton) — schematic netlist excerpt (pin names and nets, part order shuffled) for the footprints in the layout excerpt that follows; sources: Cadence DE-HDL packaged netlist, KiCad conversion of 12092022_DA0F0TMDCD0_F0T_Management_Board_D_brd_V3_OCP.brd

R119  Q_RES  33.2 1% CHIP  pkg 0402LF  page 12 : A = IRQ_BMC_LPC_SERIRQ_ESPI_GF ; B = IRQ_ESPI_LPC_SERIRQ_ALERT0_N
R836  Q_RES  33.2 1% CHIP  pkg 0402LF  page 13 : A = PWRGD_PSU_AC_PWROK ; B = PWRGD_PSU_AC_PWROK_BMC

(kicad_pcb
	(version 20260206)
	(generator "pcbnew")
	(generator_version "10.0")
	(general
		(thickness 1.6)
		(legacy_teardrops no)
	)
	(paper "A4")
	(title_block
		(title "12092022_DA0F0TMDCD0_F0T_Management_Board_D_brd_V3_OCP.brd")
		(comment 1 "Grand Teton / footprints 432-433 of 1440")
	)
	(layers
		(0 "F.Cu" signal "TOP")
		(4 "In1.Cu" signal "GND")
		(6 "In2.Cu" signal "IN1")
		(8 "In3.Cu" signal "GND1")
		(10 "In4.Cu" signal "IN2")
		(12 "In5.Cu" signal "VCC")
		(14 "In6.Cu" signal "VCC1")
		(16 "In7.Cu" signal "IN3")
		(18 "In8.Cu" signal "GND2")
		(20 "In9.Cu" signal "IN4")
		(22 "In10.Cu" signal "GND3")
		(2 "B.Cu" signal "BOTTOM")
		(9 "F.Adhes" user "F.Adhesive")
		(11 "B.Adhes" user "B.Adhesive")
		(13 "F.Paste" user "Package Geometry/Pastemask Top")
		(15 "B.Paste" user "Package Geometry/Pastemask Bottom")
		(5 "F.SilkS" user "Ref Des/Silkscreen Top")
		(7 "B.SilkS" user "Ref Des/Silkscreen Bottom")
		(1 "F.Mask" user "Board Geometry/Soldermask Top")
		(3 "B.Mask" user "Board Geometry/Soldermask Bottom")
		(17 "Dwgs.User" user "User.Drawings")
		(19 "Cmts.User" user "User.Comments")
		(21 "Eco1.User" user "User.Eco1")
		(23 "Eco2.User" user "User.Eco2")
		(25 "Edge.Cuts" user "Board Geometry/Outline")
		(27 "Margin" user)
		(31 "F.CrtYd" user "Package Geometry/Place Bound Top")
		(29 "B.CrtYd" user "Package Geometry/Place Bound Bottom")
		(35 "F.Fab" user "Ref Des/Assembly Top")
		(33 "B.Fab" user "Ref Des/Assembly Bottom")
	)
	(footprint ""
		(layer "F.Cu")
		(at 63.62827 -63.919862 -90)
		(property "Reference" "R119"
			(at 0 0 270)
			(layer "F.SilkS")
			(hide yes)
			(effects
				(font
					(size 1.27 1.27)
				)
			)
		)
		(property "Value" ""
			(at 0 0 270)
			(layer "F.Fab")
			(effects
				(font
					(size 1.27 1.27)
				)
			)
		)
		(duplicate_pad_numbers_are_jumpers no)
		(fp_line
			(start -0.7874 0.4064)
			(end -0.7874 -0.4064)
			(stroke
				(width 0.1524)
				(type default)
			)
			(layer "F.SilkS")
		)
		(fp_line
			(start 0.7874 0.4064)
			(end -0.7874 0.4064)
			(stroke
				(width 0.1524)
				(type default)
			)
			(layer "F.SilkS")
		)
		(fp_line
			(start -0.7874 -0.4064)
			(end 0.7874 -0.4064)
			(stroke
				(width 0.1524)
				(type default)
			)
			(layer "F.SilkS")
		)
		(fp_line
			(start 0.7874 -0.4064)
			(end 0.7874 0.4064)
			(stroke
				(width 0.1524)
				(type default)
			)
			(layer "F.SilkS")
		)
		(fp_line
			(start -0.67945 0.3048)
			(end -0.67945 -0.305054)
			(stroke
				(width 0.1)
				(type default)
			)
			(layer "F.Fab")
		)
		(fp_line
			(start -0.12065 0.3048)
			(end -0.67945 0.3048)
			(stroke
				(width 0.1)
				(type default)
			)
			(layer "F.Fab")
		)
		(fp_line
			(start 0.120396 0.3048)
			(end 0.120396 0.2794)
			(stroke
				(width 0.1)
				(type default)
			)
			(layer "F.Fab")
		)
		(fp_line
			(start 0.67945 0.3048)
			(end 0.120396 0.3048)
			(stroke
				(width 0.1)
				(type default)
			)
			(layer "F.Fab")
		)
		(fp_line
			(start -0.12065 0.2794)
			(end -0.12065 0.3048)
			(stroke
				(width 0.1)
				(type default)
			)
			(layer "F.Fab")
		)
		(fp_line
			(start 0.120396 0.2794)
			(end -0.12065 0.2794)
			(stroke
				(width 0.1)
				(type default)
			)
			(layer "F.Fab")
		)
		(fp_line
			(start -0.12065 -0.2794)
			(end 0.12065 -0.2794)
			(stroke
				(width 0.1)
				(type default)
			)
			(layer "F.Fab")
		)
		(fp_line
			(start 0.12065 -0.2794)
			(end 0.12065 -0.3048)
			(stroke
				(width 0.1)
				(type default)
			)
			(layer "F.Fab")
		)
		(fp_line
			(start 0.12065 -0.3048)
			(end 0.67945 -0.3048)
			(stroke
				(width 0.1)
				(type default)
			)
			(layer "F.Fab")
		)
		(fp_line
			(start 0.67945 -0.3048)
			(end 0.67945 0.3048)
			(stroke
				(width 0.1)
				(type default)
			)
			(layer "F.Fab")
		)
		(fp_line
			(start -0.67945 -0.305054)
			(end -0.12065 -0.305054)
			(stroke
				(width 0.1)
				(type default)
			)
			(layer "F.Fab")
		)
		(fp_line
			(start -0.12065 -0.305054)
			(end -0.12065 -0.2794)
			(stroke
				(width 0.1)
				(type default)
			)
			(layer "F.Fab")
		)
		(pad "1" smd circle
			(at -0.40005 0 270)
			(size 0 0)
			(layers "F.Cu" "F.Mask" "F.Paste")
			(net "IRQ_BMC_LPC_SERIRQ_ESPI_GF")
		)
		(pad "2" smd circle
			(at 0.40005 0 270)
			(size 0 0)
			(layers "F.Cu" "F.Mask" "F.Paste")
			(net "IRQ_ESPI_LPC_SERIRQ_ALERT0_N")
		)
	)
	(footprint ""
		(layer "F.Cu")
		(at 58.0644 -30.861 90)
		(property "Reference" "R836"
			(at 0 0 90)
			(layer "F.SilkS")
			(hide yes)
			(effects
				(font
					(size 1.27 1.27)
				)
			)
		)
		(property "Value" ""
			(at 0 0 90)
			(layer "F.Fab")
			(effects
				(font
					(size 1.27 1.27)
				)
			)
		)
		(duplicate_pad_numbers_are_jumpers no)
		(fp_line
			(start 0.7874 -0.4064)
			(end 0.7874 0.4064)
			(stroke
				(width 0.1524)
				(type default)
			)
			(layer "F.SilkS")
		)
		(fp_line
			(start -0.7874 -0.4064)
			(end 0.7874 -0.4064)
			(stroke
				(width 0.1524)
				(type default)
			)
			(layer "F.SilkS")
		)
		(fp_line
			(start 0.7874 0.4064)
			(end -0.7874 0.4064)
			(stroke
				(width 0.1524)
				(type default)
			)
			(layer "F.SilkS")
		)
		(fp_line
			(start -0.7874 0.4064)
			(end -0.7874 -0.4064)
			(stroke
				(width 0.1524)
				(type default)
			)
			(layer "F.SilkS")
		)
		(fp_line
			(start -0.12065 -0.305054)
			(end -0.12065 -0.2794)
			(stroke
				(width 0.1)
				(type default)
			)
			(layer "F.Fab")
		)
		(fp_line
			(start -0.67945 -0.305054)
			(end -0.12065 -0.305054)
			(stroke
				(width 0.1)
				(type default)
			)
			(layer "F.Fab")
		)
		(fp_line
			(start 0.67945 -0.3048)
			(end 0.67945 0.3048)
			(stroke
				(width 0.1)
				(type default)
			)
			(layer "F.Fab")
		)
		(fp_line
			(start 0.12065 -0.3048)
			(end 0.67945 -0.3048)
			(stroke
				(width 0.1)
				(type default)
			)
			(layer "F.Fab")
		)
		(fp_line
			(start 0.12065 -0.2794)
			(end 0.12065 -0.3048)
			(stroke
				(width 0.1)
				(type default)
			)
			(layer "F.Fab")
		)
		(fp_line
			(start -0.12065 -0.2794)
			(end 0.12065 -0.2794)
			(stroke
				(width 0.1)
				(type default)
			)
			(layer "F.Fab")
		)
		(fp_line
			(start 0.120396 0.2794)
			(end -0.12065 0.2794)
			(stroke
				(width 0.1)
				(type default)
			)
			(layer "F.Fab")
		)
		(fp_line
			(start -0.12065 0.2794)
			(end -0.12065 0.3048)
			(stroke
				(width 0.1)
				(type default)
			)
			(layer "F.Fab")
		)
		(fp_line
			(start 0.67945 0.3048)
			(end 0.120396 0.3048)
			(stroke
				(width 0.1)
				(type default)
			)
			(layer "F.Fab")
		)
		(fp_line
			(start 0.120396 0.3048)
			(end 0.120396 0.2794)
			(stroke
				(width 0.1)
				(type default)
			)
			(layer "F.Fab")
		)
		(fp_line
			(start -0.12065 0.3048)
			(end -0.67945 0.3048)
			(stroke
				(width 0.1)
				(type default)
			)
			(layer "F.Fab")
		)
		(fp_line
			(start -0.67945 0.3048)
			(end -0.67945 -0.305054)
			(stroke
				(width 0.1)
				(type default)
			)
			(layer "F.Fab")
		)
		(pad "1" smd circle
			(at -0.40005 0 90)
			(size 0 0)
			(layers "F.Cu" "F.Mask" "F.Paste")
			(net "PWRGD_PSU_AC_PWROK")
		)
		(pad "2" smd circle
			(at 0.40005 0 90)
			(size 0 0)
			(layers "F.Cu" "F.Mask" "F.Paste")
			(net "PWRGD_PSU_AC_PWROK_BMC")
		)
	)
)
